(kicad_pcb
	(version 20260206)
	(generator "pcbnew")
	(generator_version "10.0")
	(general
		(thickness 1.6)
		(legacy_teardrops no)
	)
	(paper "A4")
	(title_block
		(title "12092022_DA0F0TMDCD0_F0T_Management_Board_D_brd_V3_OCP.brd")
		(comment 1 "Grand Teton / footprints 148-153 of 1440")
	)
	(layers
		(0 "F.Cu" signal "TOP")
		(4 "In1.Cu" signal "GND")
		(6 "In2.Cu" signal "IN1")
		(8 "In3.Cu" signal "GND1")
		(10 "In4.Cu" signal "IN2")
		(12 "In5.Cu" signal "VCC")
		(14 "In6.Cu" signal "VCC1")
		(16 "In7.Cu" signal "IN3")
		(18 "In8.Cu" signal "GND2")
		(20 "In9.Cu" signal "IN4")
		(22 "In10.Cu" signal "GND3")
		(2 "B.Cu" signal "BOTTOM")
		(9 "F.Adhes" user "F.Adhesive")
		(11 "B.Adhes" user "B.Adhesive")
		(13 "F.Paste" user "Package Geometry/Pastemask Top")
		(15 "B.Paste" user "Package Geometry/Pastemask Bottom")
		(5 "F.SilkS" user "Ref Des/Silkscreen Top")
		(7 "B.SilkS" user "Ref Des/Silkscreen Bottom")
		(1 "F.Mask" user "Board Geometry/Soldermask Top")
		(3 "B.Mask" user "Board Geometry/Soldermask Bottom")
		(17 "Dwgs.User" user "User.Drawings")
		(19 "Cmts.User" user "User.Comments")
		(21 "Eco1.User" user "User.Eco1")
		(23 "Eco2.User" user "User.Eco2")
		(25 "Edge.Cuts" user "Board Geometry/Outline")
		(27 "Margin" user)
		(31 "F.CrtYd" user "Package Geometry/Place Bound Top")
		(29 "B.CrtYd" user "Package Geometry/Place Bound Bottom")
		(35 "F.Fab" user "Ref Des/Assembly Top")
		(33 "B.Fab" user "Ref Des/Assembly Bottom")
	)
	(footprint ""
		(layer "F.Cu")
		(at 70.023736 -37.288216 -90)
		(property "Reference" "C56"
			(at 0 0 270)
			(layer "F.SilkS")
			(hide yes)
			(effects
				(font
					(size 1.27 1.27)
				)
			)
		)
		(property "Value" ""
			(at 0 0 270)
			(layer "F.Fab")
			(effects
				(font
					(size 1.27 1.27)
				)
			)
		)
		(duplicate_pad_numbers_are_jumpers no)
		(fp_line
			(start -0.7874 0.4064)
			(end -0.7874 -0.4064)
			(stroke
				(width 0.1524)
				(type default)
			)
			(layer "F.SilkS")
		)
		(fp_line
			(start 0.7874 0.4064)
			(end -0.7874 0.4064)
			(stroke
				(width 0.1524)
				(type default)
			)
			(layer "F.SilkS")
		)
		(fp_line
			(start -0.7874 -0.4064)
			(end 0.7874 -0.4064)
			(stroke
				(width 0.1524)
				(type default)
			)
			(layer "F.SilkS")
		)
		(fp_line
			(start 0.7874 -0.4064)
			(end 0.7874 0.4064)
			(stroke
				(width 0.1524)
				(type default)
			)
			(layer "F.SilkS")
		)
		(fp_line
			(start -0.67945 0.3048)
			(end -0.67945 -0.305054)
			(stroke
				(width 0.1)
				(type default)
			)
			(layer "F.Fab")
		)
		(fp_line
			(start -0.12065 0.3048)
			(end -0.67945 0.3048)
			(stroke
				(width 0.1)
				(type default)
			)
			(layer "F.Fab")
		)
		(fp_line
			(start 0.120396 0.3048)
			(end 0.120396 0.2794)
			(stroke
				(width 0.1)
				(type default)
			)
			(layer "F.Fab")
		)
		(fp_line
			(start 0.67945 0.3048)
			(end 0.120396 0.3048)
			(stroke
				(width 0.1)
				(type default)
			)
			(layer "F.Fab")
		)
		(fp_line
			(start -0.12065 0.2794)
			(end -0.12065 0.3048)
			(stroke
				(width 0.1)
				(type default)
			)
			(layer "F.Fab")
		)
		(fp_line
			(start 0.120396 0.2794)
			(end -0.12065 0.2794)
			(stroke
				(width 0.1)
				(type default)
			)
			(layer "F.Fab")
		)
		(fp_line
			(start -0.12065 -0.2794)
			(end 0.12065 -0.2794)
			(stroke
				(width 0.1)
				(type default)
			)
			(layer "F.Fab")
		)
		(fp_line
			(start 0.12065 -0.2794)
			(end 0.12065 -0.3048)
			(stroke
				(width 0.1)
				(type default)
			)
			(layer "F.Fab")
		)
		(fp_line
			(start 0.12065 -0.3048)
			(end 0.67945 -0.3048)
			(stroke
				(width 0.1)
				(type default)
			)
			(layer "F.Fab")
		)
		(fp_line
			(start 0.67945 -0.3048)
			(end 0.67945 0.3048)
			(stroke
				(width 0.1)
				(type default)
			)
			(layer "F.Fab")
		)
		(fp_line
			(start -0.67945 -0.305054)
			(end -0.12065 -0.305054)
			(stroke
				(width 0.1)
				(type default)
			)
			(layer "F.Fab")
		)
		(fp_line
			(start -0.12065 -0.305054)
			(end -0.12065 -0.2794)
			(stroke
				(width 0.1)
				(type default)
			)
			(layer "F.Fab")
		)
		(pad "1" smd circle
			(at -0.40005 0 270)
			(size 0 0)
			(layers "F.Cu" "F.Mask" "F.Paste")
			(net "P1V0_STBY_PLAVDD")
		)
		(pad "2" smd circle
			(at 0.40005 0 270)
			(size 0 0)
			(layers "F.Cu" "F.Mask" "F.Paste")
			(net "GND")
		)
	)
	(footprint ""
		(layer "F.Cu")
		(at 32.8422 -108.585 -90)
		(property "Reference" "C174"
			(at 0 0 270)
			(layer "F.SilkS")
			(hide yes)
			(effects
				(font
					(size 1.27 1.27)
				)
			)
		)
		(property "Value" ""
			(at 0 0 270)
			(layer "F.Fab")
			(effects
				(font
					(size 1.27 1.27)
				)
			)
		)
		(duplicate_pad_numbers_are_jumpers no)
		(fp_line
			(start -0.7874 0.4064)
			(end -0.7874 -0.4064)
			(stroke
				(width 0.1524)
				(type default)
			)
			(layer "F.SilkS")
		)
		(fp_line
			(start 0.7874 0.4064)
			(end -0.7874 0.4064)
			(stroke
				(width 0.1524)
				(type default)
			)
			(layer "F.SilkS")
		)
		(fp_line
			(start -0.7874 -0.4064)
			(end 0.7874 -0.4064)
			(stroke
				(width 0.1524)
				(type default)
			)
			(layer "F.SilkS")
		)
		(fp_line
			(start 0.7874 -0.4064)
			(end 0.7874 0.4064)
			(stroke
				(width 0.1524)
				(type default)
			)
			(layer "F.SilkS")
		)
		(fp_line
			(start -0.67945 0.3048)
			(end -0.67945 -0.305054)
			(stroke
				(width 0.1)
				(type default)
			)
			(layer "F.Fab")
		)
		(fp_line
			(start -0.12065 0.3048)
			(end -0.67945 0.3048)
			(stroke
				(width 0.1)
				(type default)
			)
			(layer "F.Fab")
		)
		(fp_line
			(start 0.120396 0.3048)
			(end 0.120396 0.2794)
			(stroke
				(width 0.1)
				(type default)
			)
			(layer "F.Fab")
		)
		(fp_line
			(start 0.67945 0.3048)
			(end 0.120396 0.3048)
			(stroke
				(width 0.1)
				(type default)
			)
			(layer "F.Fab")
		)
		(fp_line
			(start -0.12065 0.2794)
			(end -0.12065 0.3048)
			(stroke
				(width 0.1)
				(type default)
			)
			(layer "F.Fab")
		)
		(fp_line
			(start 0.120396 0.2794)
			(end -0.12065 0.2794)
			(stroke
				(width 0.1)
				(type default)
			)
			(layer "F.Fab")
		)
		(fp_line
			(start -0.12065 -0.2794)
			(end 0.12065 -0.2794)
			(stroke
				(width 0.1)
				(type default)
			)
			(layer "F.Fab")
		)
		(fp_line
			(start 0.12065 -0.2794)
			(end 0.12065 -0.3048)
			(stroke
				(width 0.1)
				(type default)
			)
			(layer "F.Fab")
		)
		(fp_line
			(start 0.12065 -0.3048)
			(end 0.67945 -0.3048)
			(stroke
				(width 0.1)
				(type default)
			)
			(layer "F.Fab")
		)
		(fp_line
			(start 0.67945 -0.3048)
			(end 0.67945 0.3048)
			(stroke
				(width 0.1)
				(type default)
			)
			(layer "F.Fab")
		)
		(fp_line
			(start -0.67945 -0.305054)
			(end -0.12065 -0.305054)
			(stroke
				(width 0.1)
				(type default)
			)
			(layer "F.Fab")
		)
		(fp_line
			(start -0.12065 -0.305054)
			(end -0.12065 -0.2794)
			(stroke
				(width 0.1)
				(type default)
			)
			(layer "F.Fab")
		)
		(pad "1" smd circle
			(at -0.40005 0 270)
			(size 0 0)
			(layers "F.Cu" "F.Mask" "F.Paste")
			(net "P3V_BAT_R")
		)
		(pad "2" smd circle
			(at 0.40005 0 270)
			(size 0 0)
			(layers "F.Cu" "F.Mask" "F.Paste")
			(net "GND")
		)
	)
	(footprint ""
		(layer "F.Cu")
		(at 72.46493 -33.011618 90)
		(property "Reference" "R598"
			(at 0 0 90)
			(layer "F.SilkS")
			(hide yes)
			(effects
				(font
					(size 1.27 1.27)
				)
			)
		)
		(property "Value" ""
			(at 0 0 90)
			(layer "F.Fab")
			(effects
				(font
					(size 1.27 1.27)
				)
			)
		)
		(duplicate_pad_numbers_are_jumpers no)
		(fp_line
			(start 0.7874 -0.4064)
			(end 0.7874 0.4064)
			(stroke
				(width 0.1524)
				(type default)
			)
			(layer "F.SilkS")
		)
		(fp_line
			(start -0.7874 -0.4064)
			(end 0.7874 -0.4064)
			(stroke
				(width 0.1524)
				(type default)
			)
			(layer "F.SilkS")
		)
		(fp_line
			(start 0.7874 0.4064)
			(end -0.7874 0.4064)
			(stroke
				(width 0.1524)
				(type default)
			)
			(layer "F.SilkS")
		)
		(fp_line
			(start -0.7874 0.4064)
			(end -0.7874 -0.4064)
			(stroke
				(width 0.1524)
				(type default)
			)
			(layer "F.SilkS")
		)
		(fp_line
			(start -0.12065 -0.305054)
			(end -0.12065 -0.2794)
			(stroke
				(width 0.1)
				(type default)
			)
			(layer "F.Fab")
		)
		(fp_line
			(start -0.67945 -0.305054)
			(end -0.12065 -0.305054)
			(stroke
				(width 0.1)
				(type default)
			)
			(layer "F.Fab")
		)
		(fp_line
			(start 0.67945 -0.3048)
			(end 0.67945 0.3048)
			(stroke
				(width 0.1)
				(type default)
			)
			(layer "F.Fab")
		)
		(fp_line
			(start 0.12065 -0.3048)
			(end 0.67945 -0.3048)
			(stroke
				(width 0.1)
				(type default)
			)
			(layer "F.Fab")
		)
		(fp_line
			(start 0.12065 -0.2794)
			(end 0.12065 -0.3048)
			(stroke
				(width 0.1)
				(type default)
			)
			(layer "F.Fab")
		)
		(fp_line
			(start -0.12065 -0.2794)
			(end 0.12065 -0.2794)
			(stroke
				(width 0.1)
				(type default)
			)
			(layer "F.Fab")
		)
		(fp_line
			(start 0.120396 0.2794)
			(end -0.12065 0.2794)
			(stroke
				(width 0.1)
				(type default)
			)
			(layer "F.Fab")
		)
		(fp_line
			(start -0.12065 0.2794)
			(end -0.12065 0.3048)
			(stroke
				(width 0.1)
				(type default)
			)
			(layer "F.Fab")
		)
		(fp_line
			(start 0.67945 0.3048)
			(end 0.120396 0.3048)
			(stroke
				(width 0.1)
				(type default)
			)
			(layer "F.Fab")
		)
		(fp_line
			(start 0.120396 0.3048)
			(end 0.120396 0.2794)
			(stroke
				(width 0.1)
				(type default)
			)
			(layer "F.Fab")
		)
		(fp_line
			(start -0.12065 0.3048)
			(end -0.67945 0.3048)
			(stroke
				(width 0.1)
				(type default)
			)
			(layer "F.Fab")
		)
		(fp_line
			(start -0.67945 0.3048)
			(end -0.67945 -0.305054)
			(stroke
				(width 0.1)
				(type default)
			)
			(layer "F.Fab")
		)
		(pad "1" smd circle
			(at -0.40005 0 90)
			(size 0 0)
			(layers "F.Cu" "F.Mask" "F.Paste")
			(net "LED_POSTCODE_6")
		)
		(pad "2" smd circle
			(at 0.40005 0 90)
			(size 0 0)
			(layers "F.Cu" "F.Mask" "F.Paste")
			(net "LED_POSTCODE_6_R")
		)
	)
	(footprint ""
		(layer "F.Cu")
		(at 9.649968 -62.513464 180)
		(property "Reference" "PR276"
			(at 0 0 180)
			(layer "F.SilkS")
			(hide yes)
			(effects
				(font
					(size 1.27 1.27)
				)
			)
		)
		(property "Value" ""
			(at 0 0 180)
			(layer "F.Fab")
			(effects
				(font
					(size 1.27 1.27)
				)
			)
		)
		(duplicate_pad_numbers_are_jumpers no)
		(fp_line
			(start 0.7874 0.4064)
			(end -0.7874 0.4064)
			(stroke
				(width 0.1524)
				(type default)
			)
			(layer "F.SilkS")
		)
		(fp_line
			(start 0.7874 -0.4064)
			(end 0.7874 0.4064)
			(stroke
				(width 0.1524)
				(type default)
			)
			(layer "F.SilkS")
		)
		(fp_line
			(start -0.7874 0.4064)
			(end -0.7874 -0.4064)
			(stroke
				(width 0.1524)
				(type default)
			)
			(layer "F.SilkS")
		)
		(fp_line
			(start -0.7874 -0.4064)
			(end 0.7874 -0.4064)
			(stroke
				(width 0.1524)
				(type default)
			)
			(layer "F.SilkS")
		)
		(fp_line
			(start 0.67945 0.3048)
			(end 0.120396 0.3048)
			(stroke
				(width 0.1)
				(type default)
			)
			(layer "F.Fab")
		)
		(fp_line
			(start 0.67945 -0.3048)
			(end 0.67945 0.3048)
			(stroke
				(width 0.1)
				(type default)
			)
			(layer "F.Fab")
		)
		(fp_line
			(start 0.12065 -0.2794)
			(end 0.12065 -0.3048)
			(stroke
				(width 0.1)
				(type default)
			)
			(layer "F.Fab")
		)
		(fp_line
			(start 0.12065 -0.3048)
			(end 0.67945 -0.3048)
			(stroke
				(width 0.1)
				(type default)
			)
			(layer "F.Fab")
		)
		(fp_line
			(start 0.120396 0.3048)
			(end 0.120396 0.2794)
			(stroke
				(width 0.1)
				(type default)
			)
			(layer "F.Fab")
		)
		(fp_line
			(start 0.120396 0.2794)
			(end -0.12065 0.2794)
			(stroke
				(width 0.1)
				(type default)
			)
			(layer "F.Fab")
		)
		(fp_line
			(start -0.12065 0.3048)
			(end -0.67945 0.3048)
			(stroke
				(width 0.1)
				(type default)
			)
			(layer "F.Fab")
		)
		(fp_line
			(start -0.12065 0.2794)
			(end -0.12065 0.3048)
			(stroke
				(width 0.1)
				(type default)
			)
			(layer "F.Fab")
		)
		(fp_line
			(start -0.12065 -0.2794)
			(end 0.12065 -0.2794)
			(stroke
				(width 0.1)
				(type default)
			)
			(layer "F.Fab")
		)
		(fp_line
			(start -0.12065 -0.305054)
			(end -0.12065 -0.2794)
			(stroke
				(width 0.1)
				(type default)
			)
			(layer "F.Fab")
		)
		(fp_line
			(start -0.67945 0.3048)
			(end -0.67945 -0.305054)
			(stroke
				(width 0.1)
				(type default)
			)
			(layer "F.Fab")
		)
		(fp_line
			(start -0.67945 -0.305054)
			(end -0.12065 -0.305054)
			(stroke
				(width 0.1)
				(type default)
			)
			(layer "F.Fab")
		)
		(pad "1" smd circle
			(at -0.40005 0 180)
			(size 0 0)
			(layers "F.Cu" "F.Mask" "F.Paste")
			(net "GND")
		)
		(pad "2" smd circle
			(at 0.40005 0 180)
			(size 0 0)
			(layers "F.Cu" "F.Mask" "F.Paste")
			(net "P3V3_AUX_CS")
		)
	)
	(footprint ""
		(layer "F.Cu")
		(at 81.501488 -30.150308 90)
		(property "Reference" "R382"
			(at 0 0 90)
			(layer "F.SilkS")
			(hide yes)
			(effects
				(font
					(size 1.27 1.27)
				)
			)
		)
		(property "Value" ""
			(at 0 0 90)
			(layer "F.Fab")
			(effects
				(font
					(size 1.27 1.27)
				)
			)
		)
		(duplicate_pad_numbers_are_jumpers no)
		(fp_line
			(start 0.7874 -0.4064)
			(end 0.7874 0.4064)
			(stroke
				(width 0.1524)
				(type default)
			)
			(layer "F.SilkS")
		)
		(fp_line
			(start -0.7874 -0.4064)
			(end 0.7874 -0.4064)
			(stroke
				(width 0.1524)
				(type default)
			)
			(layer "F.SilkS")
		)
		(fp_line
			(start 0.7874 0.4064)
			(end -0.7874 0.4064)
			(stroke
				(width 0.1524)
				(type default)
			)
			(layer "F.SilkS")
		)
		(fp_line
			(start -0.7874 0.4064)
			(end -0.7874 -0.4064)
			(stroke
				(width 0.1524)
				(type default)
			)
			(layer "F.SilkS")
		)
		(fp_line
			(start -0.12065 -0.305054)
			(end -0.12065 -0.2794)
			(stroke
				(width 0.1)
				(type default)
			)
			(layer "F.Fab")
		)
		(fp_line
			(start -0.67945 -0.305054)
			(end -0.12065 -0.305054)
			(stroke
				(width 0.1)
				(type default)
			)
			(layer "F.Fab")
		)
		(fp_line
			(start 0.67945 -0.3048)
			(end 0.67945 0.3048)
			(stroke
				(width 0.1)
				(type default)
			)
			(layer "F.Fab")
		)
		(fp_line
			(start 0.12065 -0.3048)
			(end 0.67945 -0.3048)
			(stroke
				(width 0.1)
				(type default)
			)
			(layer "F.Fab")
		)
		(fp_line
			(start 0.12065 -0.2794)
			(end 0.12065 -0.3048)
			(stroke
				(width 0.1)
				(type default)
			)
			(layer "F.Fab")
		)
		(fp_line
			(start -0.12065 -0.2794)
			(end 0.12065 -0.2794)
			(stroke
				(width 0.1)
				(type default)
			)
			(layer "F.Fab")
		)
		(fp_line
			(start 0.120396 0.2794)
			(end -0.12065 0.2794)
			(stroke
				(width 0.1)
				(type default)
			)
			(layer "F.Fab")
		)
		(fp_line
			(start -0.12065 0.2794)
			(end -0.12065 0.3048)
			(stroke
				(width 0.1)
				(type default)
			)
			(layer "F.Fab")
		)
		(fp_line
			(start 0.67945 0.3048)
			(end 0.120396 0.3048)
			(stroke
				(width 0.1)
				(type default)
			)
			(layer "F.Fab")
		)
		(fp_line
			(start 0.120396 0.3048)
			(end 0.120396 0.2794)
			(stroke
				(width 0.1)
				(type default)
			)
			(layer "F.Fab")
		)
		(fp_line
			(start -0.12065 0.3048)
			(end -0.67945 0.3048)
			(stroke
				(width 0.1)
				(type default)
			)
			(layer "F.Fab")
		)
		(fp_line
			(start -0.67945 0.3048)
			(end -0.67945 -0.305054)
			(stroke
				(width 0.1)
				(type default)
			)
			(layer "F.Fab")
		)
		(pad "1" smd circle
			(at -0.40005 0 90)
			(size 0 0)
			(layers "F.Cu" "F.Mask" "F.Paste")
			(net "PWRGD_P3V3_AUX")
		)
		(pad "2" smd circle
			(at 0.40005 0 90)
			(size 0 0)
			(layers "F.Cu" "F.Mask" "F.Paste")
			(net "PWRGD_P3V3_AUX_R2")
		)
	)
	(footprint ""
		(layer "F.Cu")
		(at 43.966638 -22.15642 -90)
		(property "Reference" "R668"
			(at 0 0 270)
			(layer "F.SilkS")
			(hide yes)
			(effects
				(font
					(size 1.27 1.27)
				)
			)
		)
		(property "Value" ""
			(at 0 0 270)
			(layer "F.Fab")
			(effects
				(font
					(size 1.27 1.27)
				)
			)
		)
		(duplicate_pad_numbers_are_jumpers no)
		(fp_line
			(start 0.7874 0.4064)
			(end -0.7874 0.4064)
			(stroke
				(width 0.1524)
				(type default)
			)
			(layer "F.SilkS")
		)
		(fp_line
			(start -0.7874 -0.4064)
			(end 0.7874 -0.4064)
			(stroke
				(width 0.1524)
				(type default)
			)
			(layer "F.SilkS")
		)
		(fp_line
			(start -0.67945 0.3048)
			(end -0.67945 -0.305054)
			(stroke
				(width 0.1)
				(type default)
			)
			(layer "F.Fab")
		)
		(fp_line
			(start -0.12065 0.3048)
			(end -0.67945 0.3048)
			(stroke
				(width 0.1)
				(type default)
			)
			(layer "F.Fab")
		)
		(fp_line
			(start 0.120396 0.3048)
			(end 0.120396 0.2794)
			(stroke
				(width 0.1)
				(type default)
			)
			(layer "F.Fab")
		)
		(fp_line
			(start 0.67945 0.3048)
			(end 0.120396 0.3048)
			(stroke
				(width 0.1)
				(type default)
			)
			(layer "F.Fab")
		)
		(fp_line
			(start -0.12065 0.2794)
			(end -0.12065 0.3048)
			(stroke
				(width 0.1)
				(type default)
			)
			(layer "F.Fab")
		)
		(fp_line
			(start 0.120396 0.2794)
			(end -0.12065 0.2794)
			(stroke
				(width 0.1)
				(type default)
			)
			(layer "F.Fab")
		)
		(fp_line
			(start -0.12065 -0.2794)
			(end 0.12065 -0.2794)
			(stroke
				(width 0.1)
				(type default)
			)
			(layer "F.Fab")
		)
		(fp_line
			(start 0.12065 -0.2794)
			(end 0.12065 -0.3048)
			(stroke
				(width 0.1)
				(type default)
			)
			(layer "F.Fab")
		)
		(fp_line
			(start 0.12065 -0.3048)
			(end 0.67945 -0.3048)
			(stroke
				(width 0.1)
				(type default)
			)
			(layer "F.Fab")
		)
		(fp_line
			(start 0.67945 -0.3048)
			(end 0.67945 0.3048)
			(stroke
				(width 0.1)
				(type default)
			)
			(layer "F.Fab")
		)
		(fp_line
			(start -0.67945 -0.305054)
			(end -0.12065 -0.305054)
			(stroke
				(width 0.1)
				(type default)
			)
			(layer "F.Fab")
		)
		(fp_line
			(start -0.12065 -0.305054)
			(end -0.12065 -0.2794)
			(stroke
				(width 0.1)
				(type default)
			)
			(layer "F.Fab")
		)
		(pad "1" smd circle
			(at -0.40005 0 270)
			(size 0 0)
			(layers "F.Cu" "F.Mask" "F.Paste")
			(net "USB3_01_MUX_FB_RXN")
		)
		(pad "2" smd circle
			(at 0.40005 0 270)
			(size 0 0)
			(layers "F.Cu" "F.Mask" "F.Paste")
			(net "USB3_01_FB_RXN")
		)
	)
)
